(kicad_pcb
	(version 20260206)
	(generator "pcbnew")
	(generator_version "10.0")
	(general
		(thickness 1.6)
		(legacy_teardrops no)
	)
	(paper "A4")
	(title_block
		(title "dpb — 14545-sa.0730WZS0815.brd")
		(comment 1 "Honey Badger (Wiwynn) / footprints 490-496 of 1066")
	)
	(layers
		(0 "F.Cu" signal "TOP")
		(4 "In1.Cu" signal "L2GND")
		(6 "In2.Cu" signal "L3")
		(8 "In3.Cu" signal "L4VCC")
		(10 "In4.Cu" signal "L5VCC")
		(12 "In5.Cu" signal "L6")
		(14 "In6.Cu" signal "L7GND")
		(2 "B.Cu" signal "BOTTOM")
		(9 "F.Adhes" user "F.Adhesive")
		(11 "B.Adhes" user "B.Adhesive")
		(13 "F.Paste" user "Package Geometry/Pastemask Top")
		(15 "B.Paste" user "Package Geometry/Pastemask Bottom")
		(5 "F.SilkS" user "Ref Des/Silkscreen Top")
		(7 "B.SilkS" user "Ref Des/Silkscreen Bottom")
		(1 "F.Mask" user "Board Geometry/Soldermask Top")
		(3 "B.Mask" user "Board Geometry/Soldermask Bottom")
		(17 "Dwgs.User" user "User.Drawings")
		(19 "Cmts.User" user "User.Comments")
		(21 "Eco1.User" user "User.Eco1")
		(23 "Eco2.User" user "User.Eco2")
		(25 "Edge.Cuts" user "Board Geometry/Outline")
		(27 "Margin" user)
		(31 "F.CrtYd" user "Package Geometry/Place Bound Top")
		(29 "B.CrtYd" user "Package Geometry/Place Bound Bottom")
		(35 "F.Fab" user "Ref Des/Assembly Top")
		(33 "B.Fab" user "Ref Des/Assembly Bottom")
	)
	(footprint ""
		(layer "F.Cu")
		(at 11.8618 -162.4584 90)
		(property "Reference" "R360"
			(at 0 0 90)
			(layer "F.SilkS")
			(hide yes)
			(effects
				(font
					(size 1.27 1.27)
				)
			)
		)
		(property "Value" "0R2J-2-GP"
			(at 0.064008 -3.993896 90)
			(unlocked yes)
			(layer "F.Fab")
			(hide yes)
			(effects
				(font
					(size 1.016 1.016)
					(thickness 0.1524)
				)
			)
		)
		(property "Device Type" "R402H16"
			(at 0.064008 -5.517896 90)
			(unlocked yes)
			(layer "F.Fab")
			(hide yes)
			(effects
				(font
					(size 1.016 1.016)
					(thickness 0.1524)
				)
			)
		)
		(duplicate_pad_numbers_are_jumpers no)
		(fp_line
			(start 0.508 -0.9398)
			(end -0.508 -0.9398)
			(stroke
				(width 0.1524)
				(type default)
			)
			(layer "F.SilkS")
		)
		(fp_line
			(start -0.508 -0.9398)
			(end -0.508 0.9398)
			(stroke
				(width 0.1524)
				(type default)
			)
			(layer "F.SilkS")
		)
		(fp_rect
			(start -0.508 0.9398)
			(end 0.508 -0.9398)
			(stroke
				(width 0)
				(type default)
			)
			(fill no)
			(layer "F.CrtYd")
		)
		(fp_rect
			(start -0.508 0.9398)
			(end 0.508 -0.9398)
			(stroke
				(width 0)
				(type default)
			)
			(fill no)
			(layer "F.Fab")
		)
		(pad "1" smd custom
			(at 0 -0.4445 90)
			(size 0.1397 0.1397)
			(layers "F.Cu" "F.Mask" "F.Paste")
			(net "HB_EXP_A_INPUT")
			(options
				(clearance outline)
				(anchor circle)
			)
			(primitives
				(gr_poly
					(pts
						(arc
							(start -0.1778 -0.2794)
							(mid -0.249642 -0.249642)
							(end -0.2794 -0.1778)
						)
						(arc
							(start -0.2794 0.1778)
							(mid -0.249642 0.249642)
							(end -0.1778 0.2794)
						)
						(arc
							(start 0.1778 0.2794)
							(mid 0.249642 0.249642)
							(end 0.2794 0.1778)
						)
						(arc
							(start 0.2794 -0.1778)
							(mid 0.249642 -0.249642)
							(end 0.1778 -0.2794)
						)
					)
					(width 0)
					(fill yes)
				)
			)
		)
		(pad "2" smd custom
			(at 0 0.4445 90)
			(size 0.1397 0.1397)
			(layers "F.Cu" "F.Mask" "F.Paste")
			(net "SELF_1B&2B_HB")
			(options
				(clearance outline)
				(anchor circle)
			)
			(primitives
				(gr_poly
					(pts
						(arc
							(start -0.1778 -0.2794)
							(mid -0.249642 -0.249642)
							(end -0.2794 -0.1778)
						)
						(arc
							(start -0.2794 0.1778)
							(mid -0.249642 0.249642)
							(end -0.1778 0.2794)
						)
						(arc
							(start 0.1778 0.2794)
							(mid 0.249642 0.249642)
							(end 0.2794 0.1778)
						)
						(arc
							(start 0.2794 -0.1778)
							(mid 0.249642 -0.249642)
							(end 0.1778 -0.2794)
						)
					)
					(width 0)
					(fill yes)
				)
			)
		)
	)
	(footprint ""
		(layer "F.Cu")
		(at 206.31023 -383.850388 90)
		(property "Reference" "Q3"
			(at 0 0 90)
			(layer "F.SilkS")
			(hide yes)
			(effects
				(font
					(size 1.27 1.27)
				)
			)
		)
		(property "Value" "AO4406AL-GP"
			(at -3.707384 -1.5367 90)
			(unlocked yes)
			(layer "F.Fab")
			(hide yes)
			(effects
				(font
					(size 1.016 1.016)
					(thickness 0.1524)
				)
			)
		)
		(property "Device Type" "SOIC8H69"
			(at -3.707384 -3.0607 90)
			(unlocked yes)
			(layer "F.Fab")
			(hide yes)
			(effects
				(font
					(size 1.016 1.016)
					(thickness 0.1524)
				)
			)
		)
		(duplicate_pad_numbers_are_jumpers no)
		(fp_line
			(start 2.1336 -1.4224)
			(end -2.7432 -1.4224)
			(stroke
				(width 0.1524)
				(type default)
			)
			(layer "F.SilkS")
		)
		(fp_line
			(start -2.7432 -1.4224)
			(end -2.7432 1.4224)
			(stroke
				(width 0.1524)
				(type default)
			)
			(layer "F.SilkS")
		)
		(fp_line
			(start -2.7178 -0.508)
			(end -2.1844 -0.0508)
			(stroke
				(width 0.1524)
				(type default)
			)
			(layer "F.SilkS")
		)
		(fp_line
			(start -2.1844 -0.0508)
			(end -2.7178 0.508)
			(stroke
				(width 0.1524)
				(type default)
			)
			(layer "F.SilkS")
		)
		(fp_line
			(start 2.1336 1.4224)
			(end 2.1336 -1.4224)
			(stroke
				(width 0.1524)
				(type default)
			)
			(layer "F.SilkS")
		)
		(fp_line
			(start -2.7432 1.4224)
			(end 2.1336 1.4224)
			(stroke
				(width 0.1524)
				(type default)
			)
			(layer "F.SilkS")
		)
		(fp_line
			(start -2.7432 1.4224)
			(end -2.6416 1.4224)
			(stroke
				(width 0.1524)
				(type default)
			)
			(layer "F.SilkS")
		)
		(fp_line
			(start -2.6289 3.4417)
			(end -2.6289 1.4732)
			(stroke
				(width 0.381)
				(type default)
			)
			(layer "F.SilkS")
		)
		(fp_poly
			(pts
				(xy -2.2098 -1.4224) (xy -2.2098 1.4224) (xy 2.2098 1.4224) (xy 2.2098 -1.4224)
			)
			(stroke
				(width 0)
				(type default)
			)
			(fill yes)
			(layer "F.SilkS")
		)
		(fp_rect
			(start -2.450084 2.999994)
			(end 2.450084 -2.999994)
			(stroke
				(width 0)
				(type default)
			)
			(fill no)
			(layer "F.CrtYd")
		)
		(fp_poly
			(pts
				(xy -2.8194 3.6322) (xy -2.8194 -3.6322) (xy 2.8194 -3.6322) (xy 2.8194 1.18364) (xy 2.450084 1.18364)
				(xy 2.450084 -2.999994) (xy -2.450084 -2.999994) (xy -2.450084 2.999994) (xy 2.450084 2.999994)
				(xy 2.450084 1.18618) (xy 2.8194 1.18618) (xy 2.8194 3.6322)
			)
			(stroke
				(width 0)
				(type default)
			)
			(fill no)
			(layer "F.CrtYd")
		)
		(fp_rect
			(start -2.8194 3.6322)
			(end 2.8194 -3.6322)
			(stroke
				(width 0)
				(type default)
			)
			(fill no)
			(layer "F.Fab")
		)
		(pad "1" smd rect
			(at -1.905 2.54 90)
			(size 0.635 1.651)
			(layers "F.Cu" "F.Mask" "F.Paste")
			(net "P5V_HDD1")
		)
		(pad "2" smd rect
			(at -0.635 2.54 90)
			(size 0.635 1.651)
			(layers "F.Cu" "F.Mask" "F.Paste")
			(net "P5V_HDD1")
		)
		(pad "3" smd rect
			(at 0.635 2.54 90)
			(size 0.635 1.651)
			(layers "F.Cu" "F.Mask" "F.Paste")
			(net "P5V_HDD1")
		)
		(pad "4" smd rect
			(at 1.905 2.54 90)
			(size 0.635 1.651)
			(layers "F.Cu" "F.Mask" "F.Paste")
			(net "SW_HDD1_P")
		)
		(pad "5" smd rect
			(at 1.905 -2.54 90)
			(size 0.635 1.651)
			(layers "F.Cu" "F.Mask" "F.Paste")
			(net "P5VA")
		)
		(pad "6" smd rect
			(at 0.635 -2.54 90)
			(size 0.635 1.651)
			(layers "F.Cu" "F.Mask" "F.Paste")
			(net "P5VA")
		)
		(pad "7" smd rect
			(at -0.635 -2.54 90)
			(size 0.635 1.651)
			(layers "F.Cu" "F.Mask" "F.Paste")
			(net "P5VA")
		)
		(pad "8" smd rect
			(at -1.905 -2.54 90)
			(size 0.635 1.651)
			(layers "F.Cu" "F.Mask" "F.Paste")
			(net "P5VA")
		)
	)
	(footprint ""
		(layer "F.Cu")
		(at 217.9828 -86.6902 180)
		(property "Reference" "C177"
			(at 0 0 180)
			(layer "F.SilkS")
			(hide yes)
			(effects
				(font
					(size 1.27 1.27)
				)
			)
		)
		(property "Value" "SC10U25V6KX-1GP"
			(at -0.0762 -5.1308 180)
			(unlocked yes)
			(layer "F.Fab")
			(hide yes)
			(effects
				(font
					(size 1.016 1.016)
					(thickness 0.1524)
				)
			)
		)
		(property "Device Type" "C1206H71"
			(at -0.127 -6.6548 180)
			(unlocked yes)
			(layer "F.Fab")
			(hide yes)
			(effects
				(font
					(size 1.016 1.016)
					(thickness 0.1524)
				)
			)
		)
		(duplicate_pad_numbers_are_jumpers no)
		(fp_line
			(start 1.016 2.2352)
			(end -1.016 2.2352)
			(stroke
				(width 0.1524)
				(type default)
			)
			(layer "F.SilkS")
		)
		(fp_line
			(start 1.016 0.8382)
			(end 1.016 2.2352)
			(stroke
				(width 0.1524)
				(type default)
			)
			(layer "F.SilkS")
		)
		(fp_line
			(start 1.016 -2.2352)
			(end 1.016 -0.8382)
			(stroke
				(width 0.1524)
				(type default)
			)
			(layer "F.SilkS")
		)
		(fp_line
			(start -1.016 2.2352)
			(end -1.016 0.8382)
			(stroke
				(width 0.1524)
				(type default)
			)
			(layer "F.SilkS")
		)
		(fp_line
			(start -1.016 -0.8382)
			(end -1.016 -2.2352)
			(stroke
				(width 0.1524)
				(type default)
			)
			(layer "F.SilkS")
		)
		(fp_line
			(start -1.016 -2.2352)
			(end 1.016 -2.2352)
			(stroke
				(width 0.1524)
				(type default)
			)
			(layer "F.SilkS")
		)
		(fp_rect
			(start -1.0922 2.3114)
			(end 1.0922 -2.3114)
			(stroke
				(width 0)
				(type default)
			)
			(fill no)
			(layer "F.CrtYd")
		)
		(fp_poly
			(pts
				(xy 1.0922 -2.3114) (xy 1.0922 2.3114) (xy -1.0922 2.3114) (xy -1.0922 -2.3114)
			)
			(stroke
				(width 0)
				(type default)
			)
			(fill no)
			(layer "F.Fab")
		)
		(pad "1" smd rect
			(at 0 -1.397 180)
			(size 1.651 1.27)
			(layers "F.Cu" "F.Mask" "F.Paste")
			(net "P12V_HDD4")
		)
		(pad "2" smd rect
			(at 0 1.397 180)
			(size 1.651 1.27)
			(layers "F.Cu" "F.Mask" "F.Paste")
			(net "GND")
		)
	)
	(footprint ""
		(layer "F.Cu")
		(at 49.021746 -350.7867 90)
		(property "Reference" "R184"
			(at 0 0 90)
			(layer "F.SilkS")
			(hide yes)
			(effects
				(font
					(size 1.27 1.27)
				)
			)
		)
		(property "Value" "10KR2F-2-GP"
			(at 0.064008 -3.993896 90)
			(unlocked yes)
			(layer "F.Fab")
			(hide yes)
			(effects
				(font
					(size 1.016 1.016)
					(thickness 0.1524)
				)
			)
		)
		(property "Device Type" "R402H16"
			(at 0.064008 -5.517896 90)
			(unlocked yes)
			(layer "F.Fab")
			(hide yes)
			(effects
				(font
					(size 1.016 1.016)
					(thickness 0.1524)
				)
			)
		)
		(duplicate_pad_numbers_are_jumpers no)
		(fp_line
			(start 0.508 -0.9398)
			(end -0.508 -0.9398)
			(stroke
				(width 0.1524)
				(type default)
			)
			(layer "F.SilkS")
		)
		(fp_line
			(start -0.508 -0.9398)
			(end -0.508 0.9398)
			(stroke
				(width 0.1524)
				(type default)
			)
			(layer "F.SilkS")
		)
		(fp_rect
			(start -0.508 0.9398)
			(end 0.508 -0.9398)
			(stroke
				(width 0)
				(type default)
			)
			(fill no)
			(layer "F.CrtYd")
		)
		(fp_rect
			(start -0.508 0.9398)
			(end 0.508 -0.9398)
			(stroke
				(width 0)
				(type default)
			)
			(fill no)
			(layer "F.Fab")
		)
		(pad "1" smd custom
			(at 0 -0.4445 90)
			(size 0.1397 0.1397)
			(layers "F.Cu" "F.Mask" "F.Paste")
			(net "P5VB")
			(options
				(clearance outline)
				(anchor circle)
			)
			(primitives
				(gr_poly
					(pts
						(arc
							(start -0.1778 -0.2794)
							(mid -0.249642 -0.249642)
							(end -0.2794 -0.1778)
						)
						(arc
							(start -0.2794 0.1778)
							(mid -0.249642 0.249642)
							(end -0.1778 0.2794)
						)
						(arc
							(start 0.1778 0.2794)
							(mid 0.249642 0.249642)
							(end 0.2794 0.1778)
						)
						(arc
							(start 0.2794 -0.1778)
							(mid 0.249642 -0.249642)
							(end 0.1778 -0.2794)
						)
					)
					(width 0)
					(fill yes)
				)
			)
		)
		(pad "2" smd custom
			(at 0 0.4445 90)
			(size 0.1397 0.1397)
			(layers "F.Cu" "F.Mask" "F.Paste")
			(net "DRIVE_ACT_6")
			(options
				(clearance outline)
				(anchor circle)
			)
			(primitives
				(gr_poly
					(pts
						(arc
							(start -0.1778 -0.2794)
							(mid -0.249642 -0.249642)
							(end -0.2794 -0.1778)
						)
						(arc
							(start -0.2794 0.1778)
							(mid -0.249642 0.249642)
							(end -0.1778 0.2794)
						)
						(arc
							(start 0.1778 0.2794)
							(mid 0.249642 0.249642)
							(end 0.2794 0.1778)
						)
						(arc
							(start 0.2794 -0.1778)
							(mid 0.249642 -0.249642)
							(end 0.1778 -0.2794)
						)
					)
					(width 0)
					(fill yes)
				)
			)
		)
	)
	(footprint ""
		(layer "F.Cu")
		(at 75.564746 -22.761702 180)
		(property "Reference" "R303"
			(at 0 0 180)
			(layer "F.SilkS")
			(hide yes)
			(effects
				(font
					(size 1.27 1.27)
				)
			)
		)
		(property "Value" "220R3F-1-GP"
			(at -0.0254 -2.5146 180)
			(unlocked yes)
			(layer "F.Fab")
			(hide yes)
			(effects
				(font
					(size 1.016 1.016)
					(thickness 0.1524)
				)
			)
		)
		(property "Device Type" "R603H22"
			(at -0.0254 -4.0386 180)
			(unlocked yes)
			(layer "F.Fab")
			(hide yes)
			(effects
				(font
					(size 1.016 1.016)
					(thickness 0.1524)
				)
			)
		)
		(duplicate_pad_numbers_are_jumpers no)
		(fp_line
			(start 0.2032 0)
			(end 0.4826 0)
			(stroke
				(width 0.2032)
				(type default)
			)
			(layer "F.SilkS")
		)
		(fp_line
			(start -0.4826 0)
			(end -0.2032 0)
			(stroke
				(width 0.2032)
				(type default)
			)
			(layer "F.SilkS")
		)
		(fp_rect
			(start -0.5842 1.3335)
			(end 0.5842 -1.3335)
			(stroke
				(width 0)
				(type default)
			)
			(fill no)
			(layer "F.CrtYd")
		)
		(fp_rect
			(start -0.5842 1.3335)
			(end 0.5842 -1.3335)
			(stroke
				(width 0)
				(type default)
			)
			(fill no)
			(layer "F.Fab")
		)
		(pad "1" smd custom
			(at 0 -0.762 180)
			(size 0.2159 0.2159)
			(layers "F.Cu" "F.Mask" "F.Paste")
			(net "HDD_PRSNT_NET14")
			(options
				(clearance outline)
				(anchor circle)
			)
			(primitives
				(gr_poly
					(pts
						(arc
							(start -0.3302 -0.4318)
							(mid -0.402042 -0.402042)
							(end -0.4318 -0.3302)
						)
						(arc
							(start -0.4318 0.3302)
							(mid -0.402042 0.402042)
							(end -0.3302 0.4318)
						)
						(arc
							(start 0.3302 0.4318)
							(mid 0.402042 0.402042)
							(end 0.4318 0.3302)
						)
						(arc
							(start 0.4318 -0.3302)
							(mid 0.402042 -0.402042)
							(end 0.3302 -0.4318)
						)
					)
					(width 0)
					(fill yes)
				)
			)
		)
		(pad "2" smd custom
			(at 0 0.762 180)
			(size 0.2159 0.2159)
			(layers "F.Cu" "F.Mask" "F.Paste")
			(net "HDD_PRSNT14")
			(options
				(clearance outline)
				(anchor circle)
			)
			(primitives
				(gr_poly
					(pts
						(arc
							(start -0.3302 -0.4318)
							(mid -0.402042 -0.402042)
							(end -0.4318 -0.3302)
						)
						(arc
							(start -0.4318 0.3302)
							(mid -0.402042 0.402042)
							(end -0.3302 0.4318)
						)
						(arc
							(start 0.3302 0.4318)
							(mid 0.402042 0.402042)
							(end 0.4318 0.3302)
						)
						(arc
							(start 0.4318 -0.3302)
							(mid 0.402042 -0.402042)
							(end 0.3302 -0.4318)
						)
					)
					(width 0)
					(fill yes)
				)
			)
		)
	)
	(footprint ""
		(layer "F.Cu")
		(at 62.865 -274.3835)
		(property "Reference" "R383"
			(at 0 0 0)
			(layer "F.SilkS")
			(hide yes)
			(effects
				(font
					(size 1.27 1.27)
				)
			)
		)
		(property "Value" "10KR2F-2-GP"
			(at 0.064008 -3.993896 0)
			(unlocked yes)
			(layer "F.Fab")
			(hide yes)
			(effects
				(font
					(size 1.016 1.016)
					(thickness 0.1524)
				)
			)
		)
		(property "Device Type" "R402H16"
			(at 0.064008 -5.517896 0)
			(unlocked yes)
			(layer "F.Fab")
			(hide yes)
			(effects
				(font
					(size 1.016 1.016)
					(thickness 0.1524)
				)
			)
		)
		(duplicate_pad_numbers_are_jumpers no)
		(fp_line
			(start -0.508 -0.9398)
			(end -0.508 0.9398)
			(stroke
				(width 0.1524)
				(type default)
			)
			(layer "F.SilkS")
		)
		(fp_line
			(start 0.508 -0.9398)
			(end -0.508 -0.9398)
			(stroke
				(width 0.1524)
				(type default)
			)
			(layer "F.SilkS")
		)
		(fp_rect
			(start -0.508 0.9398)
			(end 0.508 -0.9398)
			(stroke
				(width 0)
				(type default)
			)
			(fill no)
			(layer "F.CrtYd")
		)
		(fp_rect
			(start -0.508 0.9398)
			(end 0.508 -0.9398)
			(stroke
				(width 0)
				(type default)
			)
			(fill no)
			(layer "F.Fab")
		)
		(pad "1" smd custom
			(at 0 -0.4445)
			(size 0.1397 0.1397)
			(layers "F.Cu" "F.Mask" "F.Paste")
			(net "P12V")
			(options
				(clearance outline)
				(anchor circle)
			)
			(primitives
				(gr_poly
					(pts
						(arc
							(start -0.1778 -0.2794)
							(mid -0.249642 -0.249642)
							(end -0.2794 -0.1778)
						)
						(arc
							(start -0.2794 0.1778)
							(mid -0.249642 0.249642)
							(end -0.1778 0.2794)
						)
						(arc
							(start 0.1778 0.2794)
							(mid 0.249642 0.249642)
							(end 0.2794 0.1778)
						)
						(arc
							(start 0.2794 -0.1778)
							(mid 0.249642 -0.249642)
							(end 0.1778 -0.2794)
						)
					)
					(width 0)
					(fill yes)
				)
			)
		)
		(pad "2" smd custom
			(at 0 0.4445)
			(size 0.1397 0.1397)
			(layers "F.Cu" "F.Mask" "F.Paste")
			(net "HDD7_LED_G")
			(options
				(clearance outline)
				(anchor circle)
			)
			(primitives
				(gr_poly
					(pts
						(arc
							(start -0.1778 -0.2794)
							(mid -0.249642 -0.249642)
							(end -0.2794 -0.1778)
						)
						(arc
							(start -0.2794 0.1778)
							(mid -0.249642 0.249642)
							(end -0.1778 0.2794)
						)
						(arc
							(start 0.1778 0.2794)
							(mid 0.249642 0.249642)
							(end 0.2794 0.1778)
						)
						(arc
							(start 0.2794 -0.1778)
							(mid 0.249642 -0.249642)
							(end 0.1778 -0.2794)
						)
					)
					(width 0)
					(fill yes)
				)
			)
		)
	)
	(footprint ""
		(layer "F.Cu")
		(at 21.742146 -255.1303 90)
		(property "Reference" "R372"
			(at 0 0 90)
			(layer "F.SilkS")
			(hide yes)
			(effects
				(font
					(size 1.27 1.27)
				)
			)
		)
		(property "Value" "4K7R2J-2-GP"
			(at 0.064008 -3.993896 90)
			(unlocked yes)
			(layer "F.Fab")
			(hide yes)
			(effects
				(font
					(size 1.016 1.016)
					(thickness 0.1524)
				)
			)
		)
		(property "Device Type" "R402H16"
			(at 0.064008 -5.517896 90)
			(unlocked yes)
			(layer "F.Fab")
			(hide yes)
			(effects
				(font
					(size 1.016 1.016)
					(thickness 0.1524)
				)
			)
		)
		(duplicate_pad_numbers_are_jumpers no)
		(fp_line
			(start 0.508 -0.9398)
			(end -0.508 -0.9398)
			(stroke
				(width 0.1524)
				(type default)
			)
			(layer "F.SilkS")
		)
		(fp_line
			(start -0.508 -0.9398)
			(end -0.508 0.9398)
			(stroke
				(width 0.1524)
				(type default)
			)
			(layer "F.SilkS")
		)
		(fp_rect
			(start -0.508 0.9398)
			(end 0.508 -0.9398)
			(stroke
				(width 0)
				(type default)
			)
			(fill no)
			(layer "F.CrtYd")
		)
		(fp_rect
			(start -0.508 0.9398)
			(end 0.508 -0.9398)
			(stroke
				(width 0)
				(type default)
			)
			(fill no)
			(layer "F.Fab")
		)
		(pad "1" smd custom
			(at 0 -0.4445 90)
			(size 0.1397 0.1397)
			(layers "F.Cu" "F.Mask" "F.Paste")
			(net "P3V3")
			(options
				(clearance outline)
				(anchor circle)
			)
			(primitives
				(gr_poly
					(pts
						(arc
							(start -0.1778 -0.2794)
							(mid -0.249642 -0.249642)
							(end -0.2794 -0.1778)
						)
						(arc
							(start -0.2794 0.1778)
							(mid -0.249642 0.249642)
							(end -0.1778 0.2794)
						)
						(arc
							(start 0.1778 0.2794)
							(mid 0.249642 0.249642)
							(end 0.2794 0.1778)
						)
						(arc
							(start 0.2794 -0.1778)
							(mid 0.249642 -0.249642)
							(end 0.1778 -0.2794)
						)
					)
					(width 0)
					(fill yes)
				)
			)
		)
		(pad "2" smd custom
			(at 0 0.4445 90)
			(size 0.1397 0.1397)
			(layers "F.Cu" "F.Mask" "F.Paste")
			(net "I2C_D_SDA")
			(options
				(clearance outline)
				(anchor circle)
			)
			(primitives
				(gr_poly
					(pts
						(arc
							(start -0.1778 -0.2794)
							(mid -0.249642 -0.249642)
							(end -0.2794 -0.1778)
						)
						(arc
							(start -0.2794 0.1778)
							(mid -0.249642 0.249642)
							(end -0.1778 0.2794)
						)
						(arc
							(start 0.1778 0.2794)
							(mid 0.249642 0.249642)
							(end 0.2794 0.1778)
						)
						(arc
							(start 0.2794 -0.1778)
							(mid 0.249642 -0.249642)
							(end 0.1778 -0.2794)
						)
					)
					(width 0)
					(fill yes)
				)
			)
		)
	)
)
